(kicad_pcb
	(version 20260206)
	(generator "pcbnew")
	(generator_version "10.0")
	(general
		(thickness 1.6)
		(legacy_teardrops no)
	)
	(paper "A4")
	(title_block
		(title "fcb — 12433-1M.1206WZS1330.brd")
		(comment 1 "Open Vault / Knox (Wiwynn) / footprints 412-416 of 495")
	)
	(layers
		(0 "F.Cu" signal "TOP")
		(4 "In1.Cu" signal "L2GND")
		(6 "In2.Cu" signal "L3VCC")
		(2 "B.Cu" signal "BOTTOM")
		(9 "F.Adhes" user "F.Adhesive")
		(11 "B.Adhes" user "B.Adhesive")
		(13 "F.Paste" user "Package Geometry/Pastemask Top")
		(15 "B.Paste" user "Package Geometry/Pastemask Bottom")
		(5 "F.SilkS" user "Ref Des/Silkscreen Top")
		(7 "B.SilkS" user "Ref Des/Silkscreen Bottom")
		(1 "F.Mask" user "Board Geometry/Soldermask Top")
		(3 "B.Mask" user "Board Geometry/Soldermask Bottom")
		(17 "Dwgs.User" user "User.Drawings")
		(19 "Cmts.User" user "User.Comments")
		(21 "Eco1.User" user "User.Eco1")
		(23 "Eco2.User" user "User.Eco2")
		(25 "Edge.Cuts" user "Board Geometry/Outline")
		(27 "Margin" user)
		(31 "F.CrtYd" user "Package Geometry/Place Bound Top")
		(29 "B.CrtYd" user "Package Geometry/Place Bound Bottom")
		(35 "F.Fab" user "Ref Des/Assembly Top")
		(33 "B.Fab" user "Ref Des/Assembly Bottom")
	)
	(footprint ""
		(layer "F.Cu")
		(at 32.004 -180.467 90)
		(property "Reference" "D13"
			(at 0 0 90)
			(layer "F.SilkS")
			(hide yes)
			(effects
				(font
					(size 1.27 1.27)
				)
			)
		)
		(property "Value" "BZG05C3V9-GP"
			(at 0.027178 -8.482076 90)
			(unlocked yes)
			(layer "F.Fab")
			(hide yes)
			(effects
				(font
					(size 1.016 1.016)
					(thickness 0.1524)
				)
			)
		)
		(property "Device Type" "D5226155AKH91"
			(at 0.027178 -10.006076 90)
			(unlocked yes)
			(layer "F.Fab")
			(hide yes)
			(effects
				(font
					(size 1.016 1.016)
					(thickness 0.1524)
				)
			)
		)
		(duplicate_pad_numbers_are_jumpers no)
		(fp_line
			(start 1.524 -3.4798)
			(end -1.524 -3.4798)
			(stroke
				(width 0.1524)
				(type default)
			)
			(layer "F.SilkS")
		)
		(fp_line
			(start -1.524 -3.4798)
			(end -1.524 3.4798)
			(stroke
				(width 0.1524)
				(type default)
			)
			(layer "F.SilkS")
		)
		(fp_line
			(start 1.524 3.4798)
			(end 1.524 -3.4798)
			(stroke
				(width 0.1524)
				(type default)
			)
			(layer "F.SilkS")
		)
		(fp_line
			(start -1.524 3.4798)
			(end 1.524 3.4798)
			(stroke
				(width 0.1524)
				(type default)
			)
			(layer "F.SilkS")
		)
		(fp_line
			(start -1.524 3.6576)
			(end 1.524 3.6576)
			(stroke
				(width 0.508)
				(type default)
			)
			(layer "F.SilkS")
		)
		(fp_rect
			(start -1.27 2.6035)
			(end 1.27 -2.6035)
			(stroke
				(width 0)
				(type default)
			)
			(fill no)
			(layer "F.CrtYd")
		)
		(fp_poly
			(pts
				(xy 1.778 -0.2921) (xy 1.27 -0.2921) (xy 1.27 -2.6035) (xy -1.27 -2.6035) (xy -1.27 2.6035) (xy 1.27 2.6035)
				(xy 1.27 -0.2794) (xy 1.778 -0.2794) (xy 1.778 3.556) (xy -1.778 3.556) (xy -1.778 -3.556) (xy 1.778 -3.556)
			)
			(stroke
				(width 0)
				(type default)
			)
			(fill no)
			(layer "F.CrtYd")
		)
		(fp_rect
			(start -1.778 3.556)
			(end 1.778 -3.556)
			(stroke
				(width 0)
				(type default)
			)
			(fill no)
			(layer "F.Fab")
		)
		(pad "A" smd rect
			(at 0 -2.212086 90)
			(size 1.8034 2.032)
			(layers "F.Cu" "F.Mask" "F.Paste")
			(net "GND")
		)
		(pad "K" smd rect
			(at 0 2.212086 90)
			(size 1.8034 2.032)
			(layers "F.Cu" "F.Mask" "F.Paste")
			(net "P3V3_AUX_BJT_B")
		)
	)
	(footprint ""
		(layer "F.Cu")
		(at 15.113 -55.118 90)
		(property "Reference" "R358"
			(at 0 0 90)
			(layer "F.SilkS")
			(hide yes)
			(effects
				(font
					(size 1.27 1.27)
				)
			)
		)
		(property "Value" "10KR2F-2-GP"
			(at 0.064008 -3.993896 90)
			(unlocked yes)
			(layer "F.Fab")
			(hide yes)
			(effects
				(font
					(size 1.016 1.016)
					(thickness 0.1524)
				)
			)
		)
		(property "Device Type" "R402H16"
			(at 0.064008 -5.517896 90)
			(unlocked yes)
			(layer "F.Fab")
			(hide yes)
			(effects
				(font
					(size 1.016 1.016)
					(thickness 0.1524)
				)
			)
		)
		(duplicate_pad_numbers_are_jumpers no)
		(fp_line
			(start 0.508 -0.9398)
			(end -0.508 -0.9398)
			(stroke
				(width 0.1524)
				(type default)
			)
			(layer "F.SilkS")
		)
		(fp_line
			(start -0.508 -0.9398)
			(end -0.508 0.9398)
			(stroke
				(width 0.1524)
				(type default)
			)
			(layer "F.SilkS")
		)
		(fp_rect
			(start -0.508 0.9398)
			(end 0.508 -0.9398)
			(stroke
				(width 0)
				(type default)
			)
			(fill no)
			(layer "F.CrtYd")
		)
		(fp_rect
			(start -0.508 0.9398)
			(end 0.508 -0.9398)
			(stroke
				(width 0)
				(type default)
			)
			(fill no)
			(layer "F.Fab")
		)
		(pad "1" smd custom
			(at 0 -0.4445 90)
			(size 0.1397 0.1397)
			(layers "F.Cu" "F.Mask" "F.Paste")
			(net "P3V3")
			(options
				(clearance outline)
				(anchor circle)
			)
			(primitives
				(gr_poly
					(pts
						(arc
							(start -0.1778 -0.2794)
							(mid -0.249642 -0.249642)
							(end -0.2794 -0.1778)
						)
						(arc
							(start -0.2794 0.1778)
							(mid -0.249642 0.249642)
							(end -0.1778 0.2794)
						)
						(arc
							(start 0.1778 0.2794)
							(mid 0.249642 0.249642)
							(end 0.2794 0.1778)
						)
						(arc
							(start 0.2794 -0.1778)
							(mid 0.249642 -0.249642)
							(end 0.1778 -0.2794)
						)
					)
					(width 0)
					(fill yes)
				)
			)
		)
		(pad "2" smd custom
			(at 0 0.4445 90)
			(size 0.1397 0.1397)
			(layers "F.Cu" "F.Mask" "F.Paste")
			(net "LOWER_TRAY_ID")
			(options
				(clearance outline)
				(anchor circle)
			)
			(primitives
				(gr_poly
					(pts
						(arc
							(start -0.1778 -0.2794)
							(mid -0.249642 -0.249642)
							(end -0.2794 -0.1778)
						)
						(arc
							(start -0.2794 0.1778)
							(mid -0.249642 0.249642)
							(end -0.1778 0.2794)
						)
						(arc
							(start 0.1778 0.2794)
							(mid 0.249642 0.249642)
							(end 0.2794 0.1778)
						)
						(arc
							(start 0.2794 -0.1778)
							(mid 0.249642 -0.249642)
							(end 0.1778 -0.2794)
						)
					)
					(width 0)
					(fill yes)
				)
			)
		)
	)
	(footprint ""
		(layer "F.Cu")
		(at 39.243 -178.054 180)
		(property "Reference" "PR45"
			(at 0 0 180)
			(layer "F.SilkS")
			(hide yes)
			(effects
				(font
					(size 1.27 1.27)
				)
			)
		)
		(property "Value" "10KR2F-2-GP"
			(at 0.064008 -3.993896 180)
			(unlocked yes)
			(layer "F.Fab")
			(hide yes)
			(effects
				(font
					(size 1.016 1.016)
					(thickness 0.1524)
				)
			)
		)
		(property "Device Type" "R402H16"
			(at 0.064008 -5.517896 180)
			(unlocked yes)
			(layer "F.Fab")
			(hide yes)
			(effects
				(font
					(size 1.016 1.016)
					(thickness 0.1524)
				)
			)
		)
		(duplicate_pad_numbers_are_jumpers no)
		(fp_line
			(start 0.508 -0.9398)
			(end -0.508 -0.9398)
			(stroke
				(width 0.1524)
				(type default)
			)
			(layer "F.SilkS")
		)
		(fp_line
			(start -0.508 -0.9398)
			(end -0.508 0.9398)
			(stroke
				(width 0.1524)
				(type default)
			)
			(layer "F.SilkS")
		)
		(fp_rect
			(start -0.508 0.9398)
			(end 0.508 -0.9398)
			(stroke
				(width 0)
				(type default)
			)
			(fill no)
			(layer "F.CrtYd")
		)
		(fp_rect
			(start -0.508 0.9398)
			(end 0.508 -0.9398)
			(stroke
				(width 0)
				(type default)
			)
			(fill no)
			(layer "F.Fab")
		)
		(pad "1" smd custom
			(at 0 -0.4445 180)
			(size 0.1397 0.1397)
			(layers "F.Cu" "F.Mask" "F.Paste")
			(net "P3V3_AUX")
			(options
				(clearance outline)
				(anchor circle)
			)
			(primitives
				(gr_poly
					(pts
						(arc
							(start -0.1778 -0.2794)
							(mid -0.249642 -0.249642)
							(end -0.2794 -0.1778)
						)
						(arc
							(start -0.2794 0.1778)
							(mid -0.249642 0.249642)
							(end -0.1778 0.2794)
						)
						(arc
							(start 0.1778 0.2794)
							(mid 0.249642 0.249642)
							(end 0.2794 0.1778)
						)
						(arc
							(start 0.2794 -0.1778)
							(mid 0.249642 -0.249642)
							(end 0.1778 -0.2794)
						)
					)
					(width 0)
					(fill yes)
				)
			)
		)
		(pad "2" smd custom
			(at 0 0.4445 180)
			(size 0.1397 0.1397)
			(layers "F.Cu" "F.Mask" "F.Paste")
			(net "TEMP_ALM#_IN_D")
			(options
				(clearance outline)
				(anchor circle)
			)
			(primitives
				(gr_poly
					(pts
						(arc
							(start -0.1778 -0.2794)
							(mid -0.249642 -0.249642)
							(end -0.2794 -0.1778)
						)
						(arc
							(start -0.2794 0.1778)
							(mid -0.249642 0.249642)
							(end -0.1778 0.2794)
						)
						(arc
							(start 0.1778 0.2794)
							(mid 0.249642 0.249642)
							(end 0.2794 0.1778)
						)
						(arc
							(start 0.2794 -0.1778)
							(mid 0.249642 -0.249642)
							(end 0.1778 -0.2794)
						)
					)
					(width 0)
					(fill yes)
				)
			)
		)
	)
	(footprint ""
		(layer "F.Cu")
		(at 16.67129 -175.540924 180)
		(property "Reference" "C9"
			(at 0 0 180)
			(layer "F.SilkS")
			(hide yes)
			(effects
				(font
					(size 1.27 1.27)
				)
			)
		)
		(property "Value" "SC1U16V3KX-5GP"
			(at 0 -2.8194 180)
			(unlocked yes)
			(layer "F.Fab")
			(hide yes)
			(effects
				(font
					(size 1.016 1.016)
					(thickness 0.1524)
				)
			)
		)
		(property "Device Type" "C603H36"
			(at 0 -4.3434 180)
			(unlocked yes)
			(layer "F.Fab")
			(hide yes)
			(effects
				(font
					(size 1.016 1.016)
					(thickness 0.1524)
				)
			)
		)
		(duplicate_pad_numbers_are_jumpers no)
		(fp_line
			(start 0.508 0)
			(end -0.508 0)
			(stroke
				(width 0.2032)
				(type default)
			)
			(layer "F.SilkS")
		)
		(fp_rect
			(start -0.5842 1.3335)
			(end 0.5842 -1.3335)
			(stroke
				(width 0)
				(type default)
			)
			(fill no)
			(layer "F.CrtYd")
		)
		(fp_rect
			(start -0.5842 1.3335)
			(end 0.5842 -1.3335)
			(stroke
				(width 0)
				(type default)
			)
			(fill no)
			(layer "F.Fab")
		)
		(pad "1" smd custom
			(at 0 -0.762 180)
			(size 0.2159 0.2159)
			(layers "F.Cu" "F.Mask" "F.Paste")
			(net "P3V3")
			(options
				(clearance outline)
				(anchor circle)
			)
			(primitives
				(gr_poly
					(pts
						(arc
							(start -0.3302 -0.4318)
							(mid -0.402042 -0.402042)
							(end -0.4318 -0.3302)
						)
						(arc
							(start -0.4318 0.3302)
							(mid -0.402042 0.402042)
							(end -0.3302 0.4318)
						)
						(arc
							(start 0.3302 0.4318)
							(mid 0.402042 0.402042)
							(end 0.4318 0.3302)
						)
						(arc
							(start 0.4318 -0.3302)
							(mid 0.402042 -0.402042)
							(end 0.3302 -0.4318)
						)
					)
					(width 0)
					(fill yes)
				)
			)
		)
		(pad "2" smd custom
			(at 0 0.762 180)
			(size 0.2159 0.2159)
			(layers "F.Cu" "F.Mask" "F.Paste")
			(net "GND")
			(options
				(clearance outline)
				(anchor circle)
			)
			(primitives
				(gr_poly
					(pts
						(arc
							(start -0.3302 -0.4318)
							(mid -0.402042 -0.402042)
							(end -0.4318 -0.3302)
						)
						(arc
							(start -0.4318 0.3302)
							(mid -0.402042 0.402042)
							(end -0.3302 0.4318)
						)
						(arc
							(start 0.3302 0.4318)
							(mid 0.402042 0.402042)
							(end 0.4318 0.3302)
						)
						(arc
							(start 0.4318 -0.3302)
							(mid 0.402042 -0.402042)
							(end 0.3302 -0.4318)
						)
					)
					(width 0)
					(fill yes)
				)
			)
		)
	)
	(footprint ""
		(layer "F.Cu")
		(at 38.67531 -153.713434)
		(property "Reference" "C1"
			(at 0 0 0)
			(layer "F.SilkS")
			(hide yes)
			(effects
				(font
					(size 1.27 1.27)
				)
			)
		)
		(property "Value" "SC10U25V5KX-GP"
			(at -0.0762 -6.1214 0)
			(unlocked yes)
			(layer "F.Fab")
			(hide yes)
			(effects
				(font
					(size 1.016 1.016)
					(thickness 0.1524)
				)
			)
		)
		(property "Device Type" "C805H56"
			(at -0.0762 -8.1534 0)
			(unlocked yes)
			(layer "F.Fab")
			(hide yes)
			(effects
				(font
					(size 1.016 1.016)
					(thickness 0.1524)
				)
			)
		)
		(duplicate_pad_numbers_are_jumpers no)
		(fp_line
			(start 0.635 0)
			(end -0.635 0)
			(stroke
				(width 0.508)
				(type default)
			)
			(layer "F.SilkS")
		)
		(fp_rect
			(start -0.9652 1.778)
			(end 0.9652 -1.778)
			(stroke
				(width 0)
				(type default)
			)
			(fill no)
			(layer "F.CrtYd")
		)
		(fp_poly
			(pts
				(xy -0.9652 -1.778) (xy 0.9652 -1.778) (xy 0.9652 1.778) (xy -0.9652 1.778)
			)
			(stroke
				(width 0)
				(type default)
			)
			(fill no)
			(layer "F.Fab")
		)
		(pad "1" smd rect
			(at 0 -0.9652)
			(size 1.397 1.143)
			(layers "F.Cu" "F.Mask" "F.Paste")
			(net "NCT7904_3VDD")
		)
		(pad "2" smd rect
			(at 0 0.9652)
			(size 1.397 1.143)
			(layers "F.Cu" "F.Mask" "F.Paste")
			(net "GND")
		)
	)
)
